(kicad_pcb
	(version 20260206)
	(generator "pcbnew")
	(generator_version "10.0")
	(general
		(thickness 1.6)
		(legacy_teardrops no)
	)
	(paper "A4")
	(title_block
		(title "04192023_DAF0TMB3IC0_F0TG_MB_C_brd_V02_OCP.brd")
		(comment 1 "Grand Teton / footprints 4408-4415 of 8354")
	)
	(layers
		(0 "F.Cu" signal "TOP")
		(4 "In1.Cu" signal "GND")
		(6 "In2.Cu" signal "IN1")
		(8 "In3.Cu" signal "GND1")
		(10 "In4.Cu" signal "IN2")
		(12 "In5.Cu" signal "GND2")
		(14 "In6.Cu" signal "IN3")
		(16 "In7.Cu" signal "GND3")
		(18 "In8.Cu" signal "VCC")
		(20 "In9.Cu" signal "VCC1")
		(22 "In10.Cu" signal "GND4")
		(24 "In11.Cu" signal "IN4")
		(26 "In12.Cu" signal "GND5")
		(28 "In13.Cu" signal "IN5")
		(30 "In14.Cu" signal "GND6")
		(32 "In15.Cu" signal "IN6")
		(34 "In16.Cu" signal "GND7")
		(2 "B.Cu" signal "BOTTOM")
		(9 "F.Adhes" user "F.Adhesive")
		(11 "B.Adhes" user "B.Adhesive")
		(13 "F.Paste" user "Package Geometry/Pastemask Top")
		(15 "B.Paste" user "Package Geometry/Pastemask Bottom")
		(5 "F.SilkS" user "Ref Des/Silkscreen Top")
		(7 "B.SilkS" user "Ref Des/Silkscreen Bottom")
		(1 "F.Mask" user "Board Geometry/Soldermask Top")
		(3 "B.Mask" user "Board Geometry/Soldermask Bottom")
		(17 "Dwgs.User" user "User.Drawings")
		(19 "Cmts.User" user "User.Comments")
		(21 "Eco1.User" user "User.Eco1")
		(23 "Eco2.User" user "User.Eco2")
		(25 "Edge.Cuts" user "Board Geometry/Outline")
		(27 "Margin" user)
		(31 "F.CrtYd" user "Package Geometry/Place Bound Top")
		(29 "B.CrtYd" user "Package Geometry/Place Bound Bottom")
		(35 "F.Fab" user "Ref Des/Assembly Top")
		(33 "B.Fab" user "Ref Des/Assembly Bottom")
	)
	(footprint ""
		(layer "F.Cu")
		(at 113.283238 -41.17975 -90)
		(property "Reference" "R6287"
			(at 0 0 270)
			(layer "F.SilkS")
			(hide yes)
			(effects
				(font
					(size 1.27 1.27)
				)
			)
		)
		(property "Value" ""
			(at 0 0 270)
			(layer "F.Fab")
			(effects
				(font
					(size 1.27 1.27)
				)
			)
		)
		(duplicate_pad_numbers_are_jumpers no)
		(fp_line
			(start -0.7874 0.4064)
			(end -0.7874 -0.4064)
			(stroke
				(width 0.1524)
				(type default)
			)
			(layer "F.SilkS")
		)
		(fp_line
			(start 0.7874 0.4064)
			(end -0.7874 0.4064)
			(stroke
				(width 0.1524)
				(type default)
			)
			(layer "F.SilkS")
		)
		(fp_line
			(start -0.7874 -0.4064)
			(end 0.7874 -0.4064)
			(stroke
				(width 0.1524)
				(type default)
			)
			(layer "F.SilkS")
		)
		(fp_line
			(start 0.7874 -0.4064)
			(end 0.7874 0.4064)
			(stroke
				(width 0.1524)
				(type default)
			)
			(layer "F.SilkS")
		)
		(fp_line
			(start -0.67945 0.3048)
			(end -0.67945 -0.305054)
			(stroke
				(width 0.1)
				(type default)
			)
			(layer "F.Fab")
		)
		(fp_line
			(start -0.12065 0.3048)
			(end -0.67945 0.3048)
			(stroke
				(width 0.1)
				(type default)
			)
			(layer "F.Fab")
		)
		(fp_line
			(start 0.120396 0.3048)
			(end 0.120396 0.2794)
			(stroke
				(width 0.1)
				(type default)
			)
			(layer "F.Fab")
		)
		(fp_line
			(start 0.67945 0.3048)
			(end 0.120396 0.3048)
			(stroke
				(width 0.1)
				(type default)
			)
			(layer "F.Fab")
		)
		(fp_line
			(start -0.12065 0.2794)
			(end -0.12065 0.3048)
			(stroke
				(width 0.1)
				(type default)
			)
			(layer "F.Fab")
		)
		(fp_line
			(start 0.120396 0.2794)
			(end -0.12065 0.2794)
			(stroke
				(width 0.1)
				(type default)
			)
			(layer "F.Fab")
		)
		(fp_line
			(start -0.12065 -0.2794)
			(end 0.12065 -0.2794)
			(stroke
				(width 0.1)
				(type default)
			)
			(layer "F.Fab")
		)
		(fp_line
			(start 0.12065 -0.2794)
			(end 0.12065 -0.3048)
			(stroke
				(width 0.1)
				(type default)
			)
			(layer "F.Fab")
		)
		(fp_line
			(start 0.12065 -0.3048)
			(end 0.67945 -0.3048)
			(stroke
				(width 0.1)
				(type default)
			)
			(layer "F.Fab")
		)
		(fp_line
			(start 0.67945 -0.3048)
			(end 0.67945 0.3048)
			(stroke
				(width 0.1)
				(type default)
			)
			(layer "F.Fab")
		)
		(fp_line
			(start -0.67945 -0.305054)
			(end -0.12065 -0.305054)
			(stroke
				(width 0.1)
				(type default)
			)
			(layer "F.Fab")
		)
		(fp_line
			(start -0.12065 -0.305054)
			(end -0.12065 -0.2794)
			(stroke
				(width 0.1)
				(type default)
			)
			(layer "F.Fab")
		)
		(pad "1" smd circle
			(at -0.40005 0 270)
			(size 0 0)
			(layers "F.Cu" "F.Mask" "F.Paste")
			(net "P3V3_AUX")
		)
		(pad "2" smd circle
			(at 0.40005 0 270)
			(size 0 0)
			(layers "F.Cu" "F.Mask" "F.Paste")
			(net "USB_HUB2_TI_PWRCTL_POL")
		)
	)
	(footprint ""
		(layer "F.Cu")
		(at 420.52494 -105.207308)
		(property "Reference" "PU205"
			(at -5.431282 -0.11684 90)
			(unlocked yes)
			(layer "F.SilkS")
			(effects
				(font
					(size 0.7874 0.5842)
					(thickness 0.1524)
				)
			)
		)
		(property "Value" ""
			(at 0 0 0)
			(layer "F.Fab")
			(effects
				(font
					(size 1.27 1.27)
				)
			)
		)
		(duplicate_pad_numbers_are_jumpers no)
		(fp_line
			(start -1.239774 -1.495298)
			(end 1.239774 -1.495298)
			(stroke
				(width 0.1524)
				(type default)
			)
			(layer "F.SilkS")
		)
		(fp_line
			(start -1.239774 1.495298)
			(end -1.239774 -1.495298)
			(stroke
				(width 0.1524)
				(type default)
			)
			(layer "F.SilkS")
		)
		(fp_line
			(start 1.239774 -1.495298)
			(end 1.239774 1.495298)
			(stroke
				(width 0.1524)
				(type default)
			)
			(layer "F.SilkS")
		)
		(fp_line
			(start 1.239774 1.495298)
			(end -1.239774 1.495298)
			(stroke
				(width 0.1524)
				(type default)
			)
			(layer "F.SilkS")
		)
		(fp_poly
			(pts
				(xy -1.827784 -0.742188) (xy -2.962402 -0.79629) (xy -2.465324 -1.682496)
			)
			(stroke
				(width 0)
				(type default)
			)
			(fill yes)
			(layer "F.SilkS")
		)
		(fp_line
			(start -0.8001 -1.050036)
			(end 0.8001 -1.050036)
			(stroke
				(width 0.1)
				(type default)
			)
			(layer "F.Fab")
		)
		(fp_line
			(start -0.8001 1.050036)
			(end -0.8001 -1.050036)
			(stroke
				(width 0.1)
				(type default)
			)
			(layer "F.Fab")
		)
		(fp_line
			(start 0.8001 -1.050036)
			(end 0.8001 1.050036)
			(stroke
				(width 0.1)
				(type default)
			)
			(layer "F.Fab")
		)
		(fp_line
			(start 0.8001 1.050036)
			(end -0.8001 1.050036)
			(stroke
				(width 0.1)
				(type default)
			)
			(layer "F.Fab")
		)
		(fp_poly
			(pts
				(xy -2.458974 -0.508) (xy -2.458974 0.508) (xy -1.442974 0)
			)
			(stroke
				(width 0)
				(type default)
			)
			(fill yes)
			(layer "F.Fab")
		)
		(pad "1_2" smd circle
			(at -0.374904 0 90)
			(size 0 0)
			(layers "F.Cu" "F.Mask" "F.Paste")
			(net "P3V3_AUX")
		)
		(pad "3" smd rect
			(at -0.499872 0.999998)
			(size 0.254 0.7112)
			(layers "F.Cu" "F.Mask" "F.Paste")
			(net "GND")
		)
		(pad "4" smd rect
			(at 0 0.999998)
			(size 0.254 0.7112)
			(layers "F.Cu" "F.Mask" "F.Paste")
			(net "P3V3_OCP_ILIMIT_1")
		)
		(pad "5" smd rect
			(at 0.499872 0.999998)
			(size 0.254 0.7112)
			(layers "F.Cu" "F.Mask" "F.Paste")
			(net "P3V3_OCP_MODE_1")
		)
		(pad "6_7" smd circle
			(at 0.374904 0 270)
			(size 0 0)
			(layers "F.Cu" "F.Mask" "F.Paste")
			(net "P3V3_OCP_SFF_R")
		)
		(pad "8" smd rect
			(at 0.499872 -0.999998)
			(size 0.254 0.7112)
			(layers "F.Cu" "F.Mask" "F.Paste")
			(net "P3V3_OCP_GATE_1")
		)
		(pad "9" smd rect
			(at 0 -0.999998)
			(size 0.254 0.7112)
			(layers "F.Cu" "F.Mask" "F.Paste")
			(net "P3V3_OCP_EN_1_R2")
		)
		(pad "10" smd rect
			(at -0.499872 -0.999998)
			(size 0.254 0.7112)
			(layers "F.Cu" "F.Mask" "F.Paste")
			(net "P3V3_OCP_DVDT_1")
		)
	)
	(footprint ""
		(layer "F.Cu")
		(at 157.686502 -349.270828 180)
		(property "Reference" "PR391"
			(at 0 0 180)
			(layer "F.SilkS")
			(hide yes)
			(effects
				(font
					(size 1.27 1.27)
				)
			)
		)
		(property "Value" ""
			(at 0 0 180)
			(layer "F.Fab")
			(effects
				(font
					(size 1.27 1.27)
				)
			)
		)
		(duplicate_pad_numbers_are_jumpers no)
		(fp_line
			(start 0.7874 0.4064)
			(end -0.7874 0.4064)
			(stroke
				(width 0.1524)
				(type default)
			)
			(layer "F.SilkS")
		)
		(fp_line
			(start 0.7874 -0.4064)
			(end 0.7874 0.4064)
			(stroke
				(width 0.1524)
				(type default)
			)
			(layer "F.SilkS")
		)
		(fp_line
			(start -0.7874 0.4064)
			(end -0.7874 -0.4064)
			(stroke
				(width 0.1524)
				(type default)
			)
			(layer "F.SilkS")
		)
		(fp_line
			(start -0.7874 -0.4064)
			(end 0.7874 -0.4064)
			(stroke
				(width 0.1524)
				(type default)
			)
			(layer "F.SilkS")
		)
		(fp_line
			(start 0.67945 0.3048)
			(end 0.120396 0.3048)
			(stroke
				(width 0.1)
				(type default)
			)
			(layer "F.Fab")
		)
		(fp_line
			(start 0.67945 -0.3048)
			(end 0.67945 0.3048)
			(stroke
				(width 0.1)
				(type default)
			)
			(layer "F.Fab")
		)
		(fp_line
			(start 0.12065 -0.2794)
			(end 0.12065 -0.3048)
			(stroke
				(width 0.1)
				(type default)
			)
			(layer "F.Fab")
		)
		(fp_line
			(start 0.12065 -0.3048)
			(end 0.67945 -0.3048)
			(stroke
				(width 0.1)
				(type default)
			)
			(layer "F.Fab")
		)
		(fp_line
			(start 0.120396 0.3048)
			(end 0.120396 0.2794)
			(stroke
				(width 0.1)
				(type default)
			)
			(layer "F.Fab")
		)
		(fp_line
			(start 0.120396 0.2794)
			(end -0.12065 0.2794)
			(stroke
				(width 0.1)
				(type default)
			)
			(layer "F.Fab")
		)
		(fp_line
			(start -0.12065 0.3048)
			(end -0.67945 0.3048)
			(stroke
				(width 0.1)
				(type default)
			)
			(layer "F.Fab")
		)
		(fp_line
			(start -0.12065 0.2794)
			(end -0.12065 0.3048)
			(stroke
				(width 0.1)
				(type default)
			)
			(layer "F.Fab")
		)
		(fp_line
			(start -0.12065 -0.2794)
			(end 0.12065 -0.2794)
			(stroke
				(width 0.1)
				(type default)
			)
			(layer "F.Fab")
		)
		(fp_line
			(start -0.12065 -0.305054)
			(end -0.12065 -0.2794)
			(stroke
				(width 0.1)
				(type default)
			)
			(layer "F.Fab")
		)
		(fp_line
			(start -0.67945 0.3048)
			(end -0.67945 -0.305054)
			(stroke
				(width 0.1)
				(type default)
			)
			(layer "F.Fab")
		)
		(fp_line
			(start -0.67945 -0.305054)
			(end -0.12065 -0.305054)
			(stroke
				(width 0.1)
				(type default)
			)
			(layer "F.Fab")
		)
		(pad "1" smd circle
			(at -0.40005 0 180)
			(size 0 0)
			(layers "F.Cu" "F.Mask" "F.Paste")
			(net "PVDD11_S3_P1_RESET_N_R")
		)
		(pad "2" smd circle
			(at 0.40005 0 180)
			(size 0 0)
			(layers "F.Cu" "F.Mask" "F.Paste")
			(net "PVDD18_S5_P1")
		)
	)
	(footprint ""
		(layer "F.Cu")
		(at 154.690826 -408.517344 -90)
		(property "Reference" "C6720"
			(at 0 0 270)
			(layer "F.SilkS")
			(hide yes)
			(effects
				(font
					(size 1.27 1.27)
				)
			)
		)
		(property "Value" ""
			(at 0 0 270)
			(layer "F.Fab")
			(effects
				(font
					(size 1.27 1.27)
				)
			)
		)
		(duplicate_pad_numbers_are_jumpers no)
		(fp_line
			(start -0.299974 0.150114)
			(end -0.299974 -0.150114)
			(stroke
				(width 0.1)
				(type default)
			)
			(layer "F.Fab")
		)
		(fp_line
			(start 0.299974 0.150114)
			(end -0.299974 0.150114)
			(stroke
				(width 0.1)
				(type default)
			)
			(layer "F.Fab")
		)
		(fp_line
			(start -0.299974 -0.150114)
			(end 0.299974 -0.150114)
			(stroke
				(width 0.1)
				(type default)
			)
			(layer "F.Fab")
		)
		(fp_line
			(start 0.299974 -0.150114)
			(end 0.299974 0.150114)
			(stroke
				(width 0.1)
				(type default)
			)
			(layer "F.Fab")
		)
		(pad "1" smd rect
			(at -0.2667 0 270)
			(size 0.3048 0.381)
			(layers "F.Cu" "F.Mask" "F.Paste")
			(net "P5E_CPU1_P2_TX_BUF_C_DN<13>")
		)
		(pad "2" smd rect
			(at 0.2667 0 270)
			(size 0.3048 0.381)
			(layers "F.Cu" "F.Mask" "F.Paste")
			(net "P5E_CPU1_P2_TX_BUF_DN<13>")
		)
	)
	(footprint ""
		(layer "F.Cu")
		(at 24.765 -364.617 180)
		(property "Reference" "C8359"
			(at 0 0 180)
			(layer "F.SilkS")
			(hide yes)
			(effects
				(font
					(size 1.27 1.27)
				)
			)
		)
		(property "Value" ""
			(at 0 0 180)
			(layer "F.Fab")
			(effects
				(font
					(size 1.27 1.27)
				)
			)
		)
		(duplicate_pad_numbers_are_jumpers no)
		(fp_line
			(start 0.7874 0.4064)
			(end -0.7874 0.4064)
			(stroke
				(width 0.1524)
				(type default)
			)
			(layer "F.SilkS")
		)
		(fp_line
			(start 0.7874 -0.4064)
			(end 0.7874 0.4064)
			(stroke
				(width 0.1524)
				(type default)
			)
			(layer "F.SilkS")
		)
		(fp_line
			(start -0.7874 0.4064)
			(end -0.7874 -0.4064)
			(stroke
				(width 0.1524)
				(type default)
			)
			(layer "F.SilkS")
		)
		(fp_line
			(start -0.7874 -0.4064)
			(end 0.7874 -0.4064)
			(stroke
				(width 0.1524)
				(type default)
			)
			(layer "F.SilkS")
		)
		(fp_line
			(start 0.67945 0.3048)
			(end 0.120396 0.3048)
			(stroke
				(width 0.1)
				(type default)
			)
			(layer "F.Fab")
		)
		(fp_line
			(start 0.67945 -0.3048)
			(end 0.67945 0.3048)
			(stroke
				(width 0.1)
				(type default)
			)
			(layer "F.Fab")
		)
		(fp_line
			(start 0.12065 -0.2794)
			(end 0.12065 -0.3048)
			(stroke
				(width 0.1)
				(type default)
			)
			(layer "F.Fab")
		)
		(fp_line
			(start 0.12065 -0.3048)
			(end 0.67945 -0.3048)
			(stroke
				(width 0.1)
				(type default)
			)
			(layer "F.Fab")
		)
		(fp_line
			(start 0.120396 0.3048)
			(end 0.120396 0.2794)
			(stroke
				(width 0.1)
				(type default)
			)
			(layer "F.Fab")
		)
		(fp_line
			(start 0.120396 0.2794)
			(end -0.12065 0.2794)
			(stroke
				(width 0.1)
				(type default)
			)
			(layer "F.Fab")
		)
		(fp_line
			(start -0.12065 0.3048)
			(end -0.67945 0.3048)
			(stroke
				(width 0.1)
				(type default)
			)
			(layer "F.Fab")
		)
		(fp_line
			(start -0.12065 0.2794)
			(end -0.12065 0.3048)
			(stroke
				(width 0.1)
				(type default)
			)
			(layer "F.Fab")
		)
		(fp_line
			(start -0.12065 -0.2794)
			(end 0.12065 -0.2794)
			(stroke
				(width 0.1)
				(type default)
			)
			(layer "F.Fab")
		)
		(fp_line
			(start -0.12065 -0.305054)
			(end -0.12065 -0.2794)
			(stroke
				(width 0.1)
				(type default)
			)
			(layer "F.Fab")
		)
		(fp_line
			(start -0.67945 0.3048)
			(end -0.67945 -0.305054)
			(stroke
				(width 0.1)
				(type default)
			)
			(layer "F.Fab")
		)
		(fp_line
			(start -0.67945 -0.305054)
			(end -0.12065 -0.305054)
			(stroke
				(width 0.1)
				(type default)
			)
			(layer "F.Fab")
		)
		(pad "1" smd circle
			(at -0.40005 0 180)
			(size 0 0)
			(layers "F.Cu" "F.Mask" "F.Paste")
			(net "PVDDCR_CPU1_P1_EN_R")
		)
		(pad "2" smd circle
			(at 0.40005 0 180)
			(size 0 0)
			(layers "F.Cu" "F.Mask" "F.Paste")
			(net "GND")
		)
	)
	(footprint ""
		(layer "F.Cu")
		(at 179.749958 -435.59984)
		(property "Reference" "H106"
			(at -6.56844 -4.312412 0)
			(unlocked yes)
			(layer "F.SilkS")
			(effects
				(font
					(size 0.7874 0.5842)
					(thickness 0.1524)
				)
				(justify left)
			)
		)
		(property "Value" ""
			(at 0 0 0)
			(layer "F.Fab")
			(effects
				(font
					(size 1.27 1.27)
				)
			)
		)
		(duplicate_pad_numbers_are_jumpers no)
		(pad "1" thru_hole circle
			(at 0 0)
			(size 10.0076 10.0076)
			(drill 5.6134)
			(layers "*.Cu" "*.Mask")
			(remove_unused_layers no)
			(net "GND")
			(clearance -1.9431)
		)
	)
	(footprint ""
		(layer "F.Cu")
		(at 397.623538 -393.86256)
		(property "Reference" "R1069"
			(at 0 0 0)
			(layer "F.SilkS")
			(hide yes)
			(effects
				(font
					(size 1.27 1.27)
				)
			)
		)
		(property "Value" ""
			(at 0 0 0)
			(layer "F.Fab")
			(effects
				(font
					(size 1.27 1.27)
				)
			)
		)
		(duplicate_pad_numbers_are_jumpers no)
		(fp_line
			(start -0.32512 -0.175006)
			(end 0.32512 -0.175006)
			(stroke
				(width 0.1)
				(type default)
			)
			(layer "F.Fab")
		)
		(fp_line
			(start -0.32512 0.175006)
			(end -0.32512 -0.175006)
			(stroke
				(width 0.1)
				(type default)
			)
			(layer "F.Fab")
		)
		(fp_line
			(start 0.32512 -0.175006)
			(end 0.32512 0.175006)
			(stroke
				(width 0.1)
				(type default)
			)
			(layer "F.Fab")
		)
		(fp_line
			(start 0.32512 0.175006)
			(end -0.32512 0.175006)
			(stroke
				(width 0.1)
				(type default)
			)
			(layer "F.Fab")
		)
		(pad "1" smd rect
			(at -0.2667 0)
			(size 0.3048 0.381)
			(layers "F.Cu" "F.Mask" "F.Paste")
			(net "P1V8_CPU0_RT_1D")
		)
		(pad "2" smd rect
			(at 0.2667 0 180)
			(size 0.3048 0.381)
			(layers "F.Cu" "F.Mask" "F.Paste")
			(net "GPIO2_RT_CPU0_P2")
		)
	)
	(footprint ""
		(layer "F.Cu")
		(at 307.220366 -429.224186 180)
		(property "Reference" "R4578"
			(at 0 0 180)
			(layer "F.SilkS")
			(hide yes)
			(effects
				(font
					(size 1.27 1.27)
				)
			)
		)
		(property "Value" ""
			(at 0 0 180)
			(layer "F.Fab")
			(effects
				(font
					(size 1.27 1.27)
				)
			)
		)
		(duplicate_pad_numbers_are_jumpers no)
		(fp_line
			(start 0.7874 0.4064)
			(end -0.7874 0.4064)
			(stroke
				(width 0.1524)
				(type default)
			)
			(layer "F.SilkS")
		)
		(fp_line
			(start 0.7874 -0.4064)
			(end 0.7874 0.4064)
			(stroke
				(width 0.1524)
				(type default)
			)
			(layer "F.SilkS")
		)
		(fp_line
			(start -0.7874 0.4064)
			(end -0.7874 -0.4064)
			(stroke
				(width 0.1524)
				(type default)
			)
			(layer "F.SilkS")
		)
		(fp_line
			(start -0.7874 -0.4064)
			(end 0.7874 -0.4064)
			(stroke
				(width 0.1524)
				(type default)
			)
			(layer "F.SilkS")
		)
		(fp_line
			(start 0.67945 0.3048)
			(end 0.120396 0.3048)
			(stroke
				(width 0.1)
				(type default)
			)
			(layer "F.Fab")
		)
		(fp_line
			(start 0.67945 -0.3048)
			(end 0.67945 0.3048)
			(stroke
				(width 0.1)
				(type default)
			)
			(layer "F.Fab")
		)
		(fp_line
			(start 0.12065 -0.2794)
			(end 0.12065 -0.3048)
			(stroke
				(width 0.1)
				(type default)
			)
			(layer "F.Fab")
		)
		(fp_line
			(start 0.12065 -0.3048)
			(end 0.67945 -0.3048)
			(stroke
				(width 0.1)
				(type default)
			)
			(layer "F.Fab")
		)
		(fp_line
			(start 0.120396 0.3048)
			(end 0.120396 0.2794)
			(stroke
				(width 0.1)
				(type default)
			)
			(layer "F.Fab")
		)
		(fp_line
			(start 0.120396 0.2794)
			(end -0.12065 0.2794)
			(stroke
				(width 0.1)
				(type default)
			)
			(layer "F.Fab")
		)
		(fp_line
			(start -0.12065 0.3048)
			(end -0.67945 0.3048)
			(stroke
				(width 0.1)
				(type default)
			)
			(layer "F.Fab")
		)
		(fp_line
			(start -0.12065 0.2794)
			(end -0.12065 0.3048)
			(stroke
				(width 0.1)
				(type default)
			)
			(layer "F.Fab")
		)
		(fp_line
			(start -0.12065 -0.2794)
			(end 0.12065 -0.2794)
			(stroke
				(width 0.1)
				(type default)
			)
			(layer "F.Fab")
		)
		(fp_line
			(start -0.12065 -0.305054)
			(end -0.12065 -0.2794)
			(stroke
				(width 0.1)
				(type default)
			)
			(layer "F.Fab")
		)
		(fp_line
			(start -0.67945 0.3048)
			(end -0.67945 -0.305054)
			(stroke
				(width 0.1)
				(type default)
			)
			(layer "F.Fab")
		)
		(fp_line
			(start -0.67945 -0.305054)
			(end -0.12065 -0.305054)
			(stroke
				(width 0.1)
				(type default)
			)
			(layer "F.Fab")
		)
		(pad "1" smd circle
			(at -0.40005 0 180)
			(size 0 0)
			(layers "F.Cu" "F.Mask" "F.Paste")
			(net "PRSNT_CABLE_GPU_A2_N")
		)
		(pad "2" smd circle
			(at 0.40005 0 180)
			(size 0 0)
			(layers "F.Cu" "F.Mask" "F.Paste")
			(net "PRSNT_CABLE_GPU_A2_ISO_N")
		)
	)
)
